(kicad_pcb
	(version 20260206)
	(generator "pcbnew")
	(generator_version "10.0")
	(general
		(thickness 1.6)
		(legacy_teardrops no)
	)
	(paper "A4")
	(title_block
		(title "peb — Lightning_PEB_BRD.brd")
		(comment 1 "Lightning (Wiwynn / Facebook NVMe JBOF) / footprints 2364-2371 of 2563")
	)
	(layers
		(0 "F.Cu" signal "TOP")
		(4 "In1.Cu" signal "L2GND")
		(6 "In2.Cu" signal "L3")
		(8 "In3.Cu" signal "L4VCC")
		(10 "In4.Cu" signal "L5VCC")
		(12 "In5.Cu" signal "L6")
		(14 "In6.Cu" signal "L7GND")
		(2 "B.Cu" signal "BOTTOM")
		(9 "F.Adhes" user "F.Adhesive")
		(11 "B.Adhes" user "B.Adhesive")
		(13 "F.Paste" user "Package Geometry/Pastemask Top")
		(15 "B.Paste" user "Package Geometry/Pastemask Bottom")
		(5 "F.SilkS" user "Ref Des/Silkscreen Top")
		(7 "B.SilkS" user "Ref Des/Silkscreen Bottom")
		(1 "F.Mask" user "Board Geometry/Soldermask Top")
		(3 "B.Mask" user "Board Geometry/Soldermask Bottom")
		(17 "Dwgs.User" user "User.Drawings")
		(19 "Cmts.User" user "User.Comments")
		(21 "Eco1.User" user "User.Eco1")
		(23 "Eco2.User" user "User.Eco2")
		(25 "Edge.Cuts" user "Board Geometry/Outline")
		(27 "Margin" user)
		(31 "F.CrtYd" user "Package Geometry/Place Bound Top")
		(29 "B.CrtYd" user "Package Geometry/Place Bound Bottom")
		(35 "F.Fab" user "Ref Des/Assembly Top")
		(33 "B.Fab" user "Ref Des/Assembly Bottom")
	)
	(footprint ""
		(layer "B.Cu")
		(at 332.9686 -181.7116)
		(property "Reference" "R3213"
			(at 0 0 0)
			(layer "B.SilkS")
			(hide yes)
			(effects
				(font
					(size 1.27 1.27)
				)
				(justify mirror)
			)
		)
		(property "Value" "0R2J-2-GP"
			(at -0.064008 -3.993896 0)
			(unlocked yes)
			(layer "B.Fab")
			(hide yes)
			(effects
				(font
					(size 1.016 1.016)
					(thickness 0.1524)
				)
				(justify mirror)
			)
		)
		(property "Device Type" "R402H16"
			(at -0.064008 -5.517896 0)
			(unlocked yes)
			(layer "B.Fab")
			(hide yes)
			(effects
				(font
					(size 1.016 1.016)
					(thickness 0.1524)
				)
				(justify mirror)
			)
		)
		(duplicate_pad_numbers_are_jumpers no)
		(fp_line
			(start -0.508 -0.9398)
			(end 0.508 -0.9398)
			(stroke
				(width 0.1524)
				(type default)
			)
			(layer "B.SilkS")
		)
		(fp_line
			(start 0.508 -0.9398)
			(end 0.508 0.9398)
			(stroke
				(width 0.1524)
				(type default)
			)
			(layer "B.SilkS")
		)
		(fp_rect
			(start 0.508 0.9398)
			(end -0.508 -0.9398)
			(stroke
				(width 0)
				(type default)
			)
			(fill no)
			(layer "B.CrtYd")
		)
		(fp_rect
			(start 0.508 0.9398)
			(end -0.508 -0.9398)
			(stroke
				(width 0)
				(type default)
			)
			(fill no)
			(layer "B.Fab")
		)
		(pad "1" smd custom
			(at 0 -0.4445 180)
			(size 0.1397 0.1397)
			(layers "B.Cu" "B.Mask" "B.Paste")
			(net "SSD_PERST#4")
			(options
				(clearance outline)
				(anchor circle)
			)
			(primitives
				(gr_poly
					(pts
						(arc
							(start -0.1778 0.2794)
							(mid -0.249642 0.249642)
							(end -0.2794 0.1778)
						)
						(arc
							(start -0.2794 -0.1778)
							(mid -0.249642 -0.249642)
							(end -0.1778 -0.2794)
						)
						(arc
							(start 0.1778 -0.2794)
							(mid 0.249642 -0.249642)
							(end 0.2794 -0.1778)
						)
						(arc
							(start 0.2794 0.1778)
							(mid 0.249642 0.249642)
							(end 0.1778 0.2794)
						)
					)
					(width 0)
					(fill yes)
				)
			)
		)
		(pad "2" smd custom
			(at 0 0.4445 180)
			(size 0.1397 0.1397)
			(layers "B.Cu" "B.Mask" "B.Paste")
			(net "SSD_PERST#0_B4")
			(options
				(clearance outline)
				(anchor circle)
			)
			(primitives
				(gr_poly
					(pts
						(arc
							(start -0.1778 0.2794)
							(mid -0.249642 0.249642)
							(end -0.2794 0.1778)
						)
						(arc
							(start -0.2794 -0.1778)
							(mid -0.249642 -0.249642)
							(end -0.1778 -0.2794)
						)
						(arc
							(start 0.1778 -0.2794)
							(mid 0.249642 -0.249642)
							(end 0.2794 -0.1778)
						)
						(arc
							(start 0.2794 0.1778)
							(mid 0.249642 0.249642)
							(end 0.1778 0.2794)
						)
					)
					(width 0)
					(fill yes)
				)
			)
		)
	)
	(footprint ""
		(layer "B.Cu")
		(at 235.585 -59.0042 90)
		(property "Reference" "C528"
			(at 0 0 90)
			(layer "B.SilkS")
			(hide yes)
			(effects
				(font
					(size 1.27 1.27)
				)
				(justify mirror)
			)
		)
		(property "Value" "SCD1U16V1KX-1-GP"
			(at 2.8321 -1.7399 90)
			(unlocked yes)
			(layer "B.Fab")
			(hide yes)
			(effects
				(font
					(size 1.016 1.016)
					(thickness 0.1524)
				)
				(justify mirror)
			)
		)
		(property "Device Type" "C0201H13"
			(at 2.8321 -3.2639 90)
			(unlocked yes)
			(layer "B.Fab")
			(hide yes)
			(effects
				(font
					(size 1.016 1.016)
					(thickness 0.1524)
				)
				(justify mirror)
			)
		)
		(duplicate_pad_numbers_are_jumpers no)
		(fp_rect
			(start 0.2794 0.6477)
			(end -0.2794 -0.6477)
			(stroke
				(width 0)
				(type default)
			)
			(fill no)
			(layer "B.CrtYd")
		)
		(fp_rect
			(start 0.2794 0.6477)
			(end -0.2794 -0.6477)
			(stroke
				(width 0)
				(type default)
			)
			(fill no)
			(layer "B.Fab")
		)
		(pad "1" smd custom
			(at 0 -0.2794 270)
			(size 0.0762 0.0762)
			(layers "B.Cu" "B.Mask" "B.Paste")
			(net "DUT_AVD_TX")
			(options
				(clearance outline)
				(anchor circle)
			)
			(primitives
				(gr_poly
					(pts
						(arc
							(start 0.1524 0.127)
							(mid 0.137521 0.162921)
							(end 0.1016 0.1778)
						)
						(arc
							(start -0.1016 0.1778)
							(mid -0.137521 0.162921)
							(end -0.1524 0.127)
						)
						(arc
							(start -0.1524 -0.127)
							(mid -0.137521 -0.162921)
							(end -0.1016 -0.1778)
						)
						(arc
							(start 0.1016 -0.1778)
							(mid 0.137521 -0.162921)
							(end 0.1524 -0.127)
						)
					)
					(width 0)
					(fill yes)
				)
			)
		)
		(pad "2" smd custom
			(at 0 0.2794 270)
			(size 0.0762 0.0762)
			(layers "B.Cu" "B.Mask" "B.Paste")
			(net "GND")
			(options
				(clearance outline)
				(anchor circle)
			)
			(primitives
				(gr_poly
					(pts
						(arc
							(start 0.1524 0.127)
							(mid 0.137521 0.162921)
							(end 0.1016 0.1778)
						)
						(arc
							(start -0.1016 0.1778)
							(mid -0.137521 0.162921)
							(end -0.1524 0.127)
						)
						(arc
							(start -0.1524 -0.127)
							(mid -0.137521 -0.162921)
							(end -0.1016 -0.1778)
						)
						(arc
							(start 0.1016 -0.1778)
							(mid 0.137521 -0.162921)
							(end 0.1524 -0.127)
						)
					)
					(width 0)
					(fill yes)
				)
			)
		)
	)
	(footprint ""
		(layer "B.Cu")
		(at 246.599964 -38.999922 -90)
		(property "Reference" "TP300"
			(at 0 0 90)
			(layer "B.SilkS")
			(hide yes)
			(effects
				(font
					(size 1.27 1.27)
				)
				(justify mirror)
			)
		)
		(property "Value" "TPAD28-2-GP"
			(at 0.0127 -1.6637 270)
			(unlocked yes)
			(layer "B.Fab")
			(hide yes)
			(effects
				(font
					(size 1.016 1.016)
					(thickness 0.1524)
				)
				(justify mirror)
			)
		)
		(property "Device Type" "TPAD28"
			(at 0.0127 -3.1877 270)
			(unlocked yes)
			(layer "B.Fab")
			(hide yes)
			(effects
				(font
					(size 1.016 1.016)
					(thickness 0.1524)
				)
				(justify mirror)
			)
		)
		(duplicate_pad_numbers_are_jumpers no)
		(fp_poly
			(pts
				(arc
					(start 0 -0.3556)
					(mid 0 0.3556)
					(end 0 -0.3556)
				)
			)
			(stroke
				(width 0)
				(type default)
			)
			(fill no)
			(layer "B.CrtYd")
		)
		(fp_poly
			(pts
				(arc
					(start 0 -0.6096)
					(mid 0 0.6096)
					(end 0 -0.6096)
				)
			)
			(stroke
				(width 0)
				(type default)
			)
			(fill no)
			(layer "B.Fab")
		)
		(pad "1" smd circle
			(at 0 0 90)
			(size 0.7112 0.7112)
			(layers "B.Cu" "B.Mask" "B.Paste")
			(net "TWI_SRST#9")
		)
	)
	(footprint ""
		(layer "B.Cu")
		(at 49.1871 -116.032788 180)
		(property "Reference" "R462"
			(at 0 0 0)
			(layer "B.SilkS")
			(hide yes)
			(effects
				(font
					(size 1.27 1.27)
				)
				(justify mirror)
			)
		)
		(property "Value" "0R2J-2-GP"
			(at -0.064008 -3.993896 180)
			(unlocked yes)
			(layer "B.Fab")
			(hide yes)
			(effects
				(font
					(size 1.016 1.016)
					(thickness 0.1524)
				)
				(justify mirror)
			)
		)
		(property "Device Type" "R402H16"
			(at -0.064008 -5.517896 180)
			(unlocked yes)
			(layer "B.Fab")
			(hide yes)
			(effects
				(font
					(size 1.016 1.016)
					(thickness 0.1524)
				)
				(justify mirror)
			)
		)
		(duplicate_pad_numbers_are_jumpers no)
		(fp_line
			(start 0.508 -0.9398)
			(end 0.508 0.9398)
			(stroke
				(width 0.1524)
				(type default)
			)
			(layer "B.SilkS")
		)
		(fp_line
			(start -0.508 -0.9398)
			(end 0.508 -0.9398)
			(stroke
				(width 0.1524)
				(type default)
			)
			(layer "B.SilkS")
		)
		(fp_rect
			(start 0.508 0.9398)
			(end -0.508 -0.9398)
			(stroke
				(width 0)
				(type default)
			)
			(fill no)
			(layer "B.CrtYd")
		)
		(fp_rect
			(start 0.508 0.9398)
			(end -0.508 -0.9398)
			(stroke
				(width 0)
				(type default)
			)
			(fill no)
			(layer "B.Fab")
		)
		(pad "1" smd custom
			(at 0 -0.4445)
			(size 0.1397 0.1397)
			(layers "B.Cu" "B.Mask" "B.Paste")
			(net "BMC_I2C9_CLKBUF2_SDA")
			(options
				(clearance outline)
				(anchor circle)
			)
			(primitives
				(gr_poly
					(pts
						(arc
							(start -0.1778 0.2794)
							(mid -0.249642 0.249642)
							(end -0.2794 0.1778)
						)
						(arc
							(start -0.2794 -0.1778)
							(mid -0.249642 -0.249642)
							(end -0.1778 -0.2794)
						)
						(arc
							(start 0.1778 -0.2794)
							(mid 0.249642 -0.249642)
							(end 0.2794 -0.1778)
						)
						(arc
							(start 0.2794 0.1778)
							(mid 0.249642 0.249642)
							(end 0.1778 0.2794)
						)
					)
					(width 0)
					(fill yes)
				)
			)
		)
		(pad "2" smd custom
			(at 0 0.4445)
			(size 0.1397 0.1397)
			(layers "B.Cu" "B.Mask" "B.Paste")
			(net "BMC0_SMB9_DAT")
			(options
				(clearance outline)
				(anchor circle)
			)
			(primitives
				(gr_poly
					(pts
						(arc
							(start -0.1778 0.2794)
							(mid -0.249642 0.249642)
							(end -0.2794 0.1778)
						)
						(arc
							(start -0.2794 -0.1778)
							(mid -0.249642 -0.249642)
							(end -0.1778 -0.2794)
						)
						(arc
							(start 0.1778 -0.2794)
							(mid 0.249642 -0.249642)
							(end 0.2794 -0.1778)
						)
						(arc
							(start 0.2794 0.1778)
							(mid 0.249642 0.249642)
							(end 0.1778 0.2794)
						)
					)
					(width 0)
					(fill yes)
				)
			)
		)
	)
	(footprint ""
		(layer "B.Cu")
		(at 243.586 -56.9976 -90)
		(property "Reference" "C514"
			(at 0 0 90)
			(layer "B.SilkS")
			(hide yes)
			(effects
				(font
					(size 1.27 1.27)
				)
				(justify mirror)
			)
		)
		(property "Value" "SCD1U16V1KX-1-GP"
			(at 2.8321 -1.7399 270)
			(unlocked yes)
			(layer "B.Fab")
			(hide yes)
			(effects
				(font
					(size 1.016 1.016)
					(thickness 0.1524)
				)
				(justify mirror)
			)
		)
		(property "Device Type" "C0201H13"
			(at 2.8321 -3.2639 270)
			(unlocked yes)
			(layer "B.Fab")
			(hide yes)
			(effects
				(font
					(size 1.016 1.016)
					(thickness 0.1524)
				)
				(justify mirror)
			)
		)
		(duplicate_pad_numbers_are_jumpers no)
		(fp_rect
			(start 0.2794 0.6477)
			(end -0.2794 -0.6477)
			(stroke
				(width 0)
				(type default)
			)
			(fill no)
			(layer "B.CrtYd")
		)
		(fp_rect
			(start 0.2794 0.6477)
			(end -0.2794 -0.6477)
			(stroke
				(width 0)
				(type default)
			)
			(fill no)
			(layer "B.Fab")
		)
		(pad "1" smd custom
			(at 0 -0.2794 90)
			(size 0.0762 0.0762)
			(layers "B.Cu" "B.Mask" "B.Paste")
			(net "DUT_AVD_TX")
			(options
				(clearance outline)
				(anchor circle)
			)
			(primitives
				(gr_poly
					(pts
						(arc
							(start 0.1524 0.127)
							(mid 0.137521 0.162921)
							(end 0.1016 0.1778)
						)
						(arc
							(start -0.1016 0.1778)
							(mid -0.137521 0.162921)
							(end -0.1524 0.127)
						)
						(arc
							(start -0.1524 -0.127)
							(mid -0.137521 -0.162921)
							(end -0.1016 -0.1778)
						)
						(arc
							(start 0.1016 -0.1778)
							(mid 0.137521 -0.162921)
							(end 0.1524 -0.127)
						)
					)
					(width 0)
					(fill yes)
				)
			)
		)
		(pad "2" smd custom
			(at 0 0.2794 90)
			(size 0.0762 0.0762)
			(layers "B.Cu" "B.Mask" "B.Paste")
			(net "GND")
			(options
				(clearance outline)
				(anchor circle)
			)
			(primitives
				(gr_poly
					(pts
						(arc
							(start 0.1524 0.127)
							(mid 0.137521 0.162921)
							(end 0.1016 0.1778)
						)
						(arc
							(start -0.1016 0.1778)
							(mid -0.137521 0.162921)
							(end -0.1524 0.127)
						)
						(arc
							(start -0.1524 -0.127)
							(mid -0.137521 -0.162921)
							(end -0.1016 -0.1778)
						)
						(arc
							(start 0.1016 -0.1778)
							(mid 0.137521 -0.162921)
							(end 0.1524 -0.127)
						)
					)
					(width 0)
					(fill yes)
				)
			)
		)
	)
	(footprint ""
		(layer "B.Cu")
		(at 272.161 -9.271 90)
		(property "Reference" "R2964"
			(at 0 0 90)
			(layer "B.SilkS")
			(hide yes)
			(effects
				(font
					(size 1.27 1.27)
				)
				(justify mirror)
			)
		)
		(property "Value" "0R2J-2-GP"
			(at -0.064008 -3.993896 90)
			(unlocked yes)
			(layer "B.Fab")
			(hide yes)
			(effects
				(font
					(size 1.016 1.016)
					(thickness 0.1524)
				)
				(justify mirror)
			)
		)
		(property "Device Type" "R402H16"
			(at -0.064008 -5.517896 90)
			(unlocked yes)
			(layer "B.Fab")
			(hide yes)
			(effects
				(font
					(size 1.016 1.016)
					(thickness 0.1524)
				)
				(justify mirror)
			)
		)
		(duplicate_pad_numbers_are_jumpers no)
		(fp_line
			(start 0.508 -0.9398)
			(end 0.508 0.9398)
			(stroke
				(width 0.1524)
				(type default)
			)
			(layer "B.SilkS")
		)
		(fp_line
			(start -0.508 -0.9398)
			(end 0.508 -0.9398)
			(stroke
				(width 0.1524)
				(type default)
			)
			(layer "B.SilkS")
		)
		(fp_rect
			(start 0.508 0.9398)
			(end -0.508 -0.9398)
			(stroke
				(width 0)
				(type default)
			)
			(fill no)
			(layer "B.CrtYd")
		)
		(fp_rect
			(start 0.508 0.9398)
			(end -0.508 -0.9398)
			(stroke
				(width 0)
				(type default)
			)
			(fill no)
			(layer "B.Fab")
		)
		(pad "1" smd custom
			(at 0 -0.4445 270)
			(size 0.1397 0.1397)
			(layers "B.Cu" "B.Mask" "B.Paste")
			(net "PCIE_REFCLK_H0_P")
			(options
				(clearance outline)
				(anchor circle)
			)
			(primitives
				(gr_poly
					(pts
						(arc
							(start -0.1778 0.2794)
							(mid -0.249642 0.249642)
							(end -0.2794 0.1778)
						)
						(arc
							(start -0.2794 -0.1778)
							(mid -0.249642 -0.249642)
							(end -0.1778 -0.2794)
						)
						(arc
							(start 0.1778 -0.2794)
							(mid 0.249642 -0.249642)
							(end 0.2794 -0.1778)
						)
						(arc
							(start 0.2794 0.1778)
							(mid 0.249642 0.249642)
							(end 0.1778 0.2794)
						)
					)
					(width 0)
					(fill yes)
				)
			)
		)
		(pad "2" smd custom
			(at 0 0.4445 270)
			(size 0.1397 0.1397)
			(layers "B.Cu" "B.Mask" "B.Paste")
			(net "PCIE_REFCLK_H0_P_R")
			(options
				(clearance outline)
				(anchor circle)
			)
			(primitives
				(gr_poly
					(pts
						(arc
							(start -0.1778 0.2794)
							(mid -0.249642 0.249642)
							(end -0.2794 0.1778)
						)
						(arc
							(start -0.2794 -0.1778)
							(mid -0.249642 -0.249642)
							(end -0.1778 -0.2794)
						)
						(arc
							(start 0.1778 -0.2794)
							(mid 0.249642 -0.249642)
							(end 0.2794 -0.1778)
						)
						(arc
							(start 0.2794 0.1778)
							(mid 0.249642 0.249642)
							(end 0.1778 0.2794)
						)
					)
					(width 0)
					(fill yes)
				)
			)
		)
	)
	(footprint ""
		(layer "B.Cu")
		(at 58.565288 -116.995702)
		(property "Reference" "R475"
			(at 0 0 0)
			(layer "B.SilkS")
			(hide yes)
			(effects
				(font
					(size 1.27 1.27)
				)
				(justify mirror)
			)
		)
		(property "Value" "4K7R2F-GP"
			(at -0.064008 -3.993896 0)
			(unlocked yes)
			(layer "B.Fab")
			(hide yes)
			(effects
				(font
					(size 1.016 1.016)
					(thickness 0.1524)
				)
				(justify mirror)
			)
		)
		(property "Device Type" "R402H16"
			(at -0.064008 -5.517896 0)
			(unlocked yes)
			(layer "B.Fab")
			(hide yes)
			(effects
				(font
					(size 1.016 1.016)
					(thickness 0.1524)
				)
				(justify mirror)
			)
		)
		(duplicate_pad_numbers_are_jumpers no)
		(fp_line
			(start -0.508 -0.9398)
			(end 0.508 -0.9398)
			(stroke
				(width 0.1524)
				(type default)
			)
			(layer "B.SilkS")
		)
		(fp_line
			(start 0.508 -0.9398)
			(end 0.508 0.9398)
			(stroke
				(width 0.1524)
				(type default)
			)
			(layer "B.SilkS")
		)
		(fp_rect
			(start 0.508 0.9398)
			(end -0.508 -0.9398)
			(stroke
				(width 0)
				(type default)
			)
			(fill no)
			(layer "B.CrtYd")
		)
		(fp_rect
			(start 0.508 0.9398)
			(end -0.508 -0.9398)
			(stroke
				(width 0)
				(type default)
			)
			(fill no)
			(layer "B.Fab")
		)
		(pad "1" smd custom
			(at 0 -0.4445 180)
			(size 0.1397 0.1397)
			(layers "B.Cu" "B.Mask" "B.Paste")
			(net "BMC_I2C3_MINI3_SCL_S")
			(options
				(clearance outline)
				(anchor circle)
			)
			(primitives
				(gr_poly
					(pts
						(arc
							(start -0.1778 0.2794)
							(mid -0.249642 0.249642)
							(end -0.2794 0.1778)
						)
						(arc
							(start -0.2794 -0.1778)
							(mid -0.249642 -0.249642)
							(end -0.1778 -0.2794)
						)
						(arc
							(start 0.1778 -0.2794)
							(mid 0.249642 -0.249642)
							(end 0.2794 -0.1778)
						)
						(arc
							(start 0.2794 0.1778)
							(mid 0.249642 0.249642)
							(end 0.1778 0.2794)
						)
					)
					(width 0)
					(fill yes)
				)
			)
		)
		(pad "2" smd custom
			(at 0 0.4445 180)
			(size 0.1397 0.1397)
			(layers "B.Cu" "B.Mask" "B.Paste")
			(net "P3V3_STBY")
			(options
				(clearance outline)
				(anchor circle)
			)
			(primitives
				(gr_poly
					(pts
						(arc
							(start -0.1778 0.2794)
							(mid -0.249642 0.249642)
							(end -0.2794 0.1778)
						)
						(arc
							(start -0.2794 -0.1778)
							(mid -0.249642 -0.249642)
							(end -0.1778 -0.2794)
						)
						(arc
							(start 0.1778 -0.2794)
							(mid 0.249642 -0.249642)
							(end 0.2794 -0.1778)
						)
						(arc
							(start 0.2794 0.1778)
							(mid 0.249642 0.249642)
							(end 0.1778 0.2794)
						)
					)
					(width 0)
					(fill yes)
				)
			)
		)
	)
	(footprint ""
		(layer "B.Cu")
		(at 131.843526 -199.889618)
		(property "Reference" "C418"
			(at 0 0 0)
			(layer "B.SilkS")
			(hide yes)
			(effects
				(font
					(size 1.27 1.27)
				)
				(justify mirror)
			)
		)
		(property "Value" "SCD1U25V2KX-2-GP"
			(at -1.1811 -2.7051 0)
			(unlocked yes)
			(layer "B.Fab")
			(hide yes)
			(effects
				(font
					(size 1.016 1.016)
					(thickness 0.1524)
				)
				(justify mirror)
			)
		)
		(property "Device Type" "C402H22"
			(at -1.1811 -4.2291 0)
			(unlocked yes)
			(layer "B.Fab")
			(hide yes)
			(effects
				(font
					(size 1.016 1.016)
					(thickness 0.1524)
				)
				(justify mirror)
			)
		)
		(duplicate_pad_numbers_are_jumpers no)
		(fp_rect
			(start 0.4318 0.9525)
			(end -0.4318 -0.9525)
			(stroke
				(width 0)
				(type default)
			)
			(fill no)
			(layer "B.CrtYd")
		)
		(fp_rect
			(start 0.4318 0.9525)
			(end -0.4318 -0.9525)
			(stroke
				(width 0)
				(type default)
			)
			(fill no)
			(layer "B.Fab")
		)
		(pad "1" smd custom
			(at 0 -0.4445 180)
			(size 0.1524 0.1524)
			(layers "B.Cu" "B.Mask" "B.Paste")
			(net "P3V3_STBY")
			(options
				(clearance outline)
				(anchor circle)
			)
			(primitives
				(gr_poly
					(pts
						(arc
							(start 0.3048 0.2032)
							(mid 0.275042 0.275042)
							(end 0.2032 0.3048)
						)
						(arc
							(start -0.2032 0.3048)
							(mid -0.275042 0.275042)
							(end -0.3048 0.2032)
						)
						(arc
							(start -0.3048 -0.2032)
							(mid -0.275042 -0.275042)
							(end -0.2032 -0.3048)
						)
						(arc
							(start 0.2032 -0.3048)
							(mid 0.275042 -0.275042)
							(end 0.3048 -0.2032)
						)
					)
					(width 0)
					(fill yes)
				)
			)
		)
		(pad "2" smd custom
			(at 0 0.4445 180)
			(size 0.1524 0.1524)
			(layers "B.Cu" "B.Mask" "B.Paste")
			(net "GND")
			(options
				(clearance outline)
				(anchor circle)
			)
			(primitives
				(gr_poly
					(pts
						(arc
							(start 0.3048 0.2032)
							(mid 0.275042 0.275042)
							(end 0.2032 0.3048)
						)
						(arc
							(start -0.2032 0.3048)
							(mid -0.275042 0.275042)
							(end -0.3048 0.2032)
						)
						(arc
							(start -0.3048 -0.2032)
							(mid -0.275042 -0.275042)
							(end -0.2032 -0.3048)
						)
						(arc
							(start 0.2032 -0.3048)
							(mid 0.275042 -0.275042)
							(end 0.3048 -0.2032)
						)
					)
					(width 0)
					(fill yes)
				)
			)
		)
	)
)
